2 7
DRAWING NO.
SCALE DWG
DO NOT 
MODEL
NAME
APPD
CKD
DSN
DRN
SHEET
SIGNDESCRIPTION DATE
Wiwynn Corporation
A
B
F
MATERIAL
FINISH
OF
DIM IN  mm
REV
15 16 17141 3 4 5 6 8 9 10 11 12 13 1918 2120
K
J
I
L
M
N
O
C
D
E
H
G
20 2118 19131211109865431 14 17161572
G
H
E
D
C
O
N
M
L
I
J
K
F
B
A
(NPTH)3.18
(NPTH)2.49
(NPTH)2.49
(NPTH)3.18
(PTH)3.55
0.00
2-335.40
0.00
2-335.40
2-14.00 2-14.00
2-31.00 2-31.00
(PTH)3.55 (PTH)3.55 (PTH)3.55
(PTH)3.55
(PTH)3.55
14.00
20.00
(NPTH)2.80
(NPTH)2.80
(NPTH)2.80
(NPTH)2.80
(PAD)(NO TRACE AT ALL LAYERS)9.50
(PAD)(NO TRACE AT ALL LAYERS)9.50
(PAD)(NO TRACE AT ALL LAYERS)9.50
(PAD)(NO TRACE AT ALL LAYERS)9.50
(PAD)(NO TRACE AT ALL LAYERS)9.50
(PAD)(NO TRACE AT ALL LAYERS)9.50
(PTH)5.30
11.00
14.15
6.00
69.80 69.80
184.80 184.80 184.80
100.00 100.00
69.80 69.80
184.80 184.80 184.80
299.80299.80299.80299.80
181.80
250.00250.00
210.00
24.00 24.00
295.21
(NPTH)3.50
(NO TRACE AT ALL LAYERS)7.50
0.00
0.00
2-44.00
107.10
2-170.20
2-341.30
404.40
2-467.50
96.33
159.33
189.80
300.20
330.68
393.68
33.33
96.33
159.33
330.68
393.68
456.68
244.20244.20
189.80
96.33
159.33
330.68
393.68
3.00
488.45
371.00
72.30
126.30
363.70
417.70
371.00
62.62
67.70
129.92
135.00
198.00
252.00
3-380.00
272.45
276.75
360.00
491.45
280.55
127.83
425.18
181.80
66.80
(NO TRACE AT ALL LAYERS)28.00
(NO TRACE AT ALL LAYERS)28.00
(NO TRACE AT ALL LAYERS)28.00
(NO TRACE AT ALL LAYERS)28.00 (NPTH)10.30 0.10
(NPTH)10.30 0.10
386.00
16.25
24.75
173.85
182.35
307.65
316.15
465.25
473.75
4-382.30
33.33
456.68
33.33
456.68
69.80 69.80
299.80299.80
199.00
311.00
BryceCanyon Bryce Canyon R.DPB 
CD 
Jess Wang 6/6
2017
 Jess Wang  6/6
2017
TU863+VLP / NPG170D+VLP T=2.36mm 
1 1  Lenny Kao 
 Lenny Kao  
6/6
2017
6/6
2017
16317-1 VERSION B 2017-06-07
16317-1 VERSION A 2017-06-06
COMPONENT SIDE
SOLDER SIDE
SEE DETAIL  B
Q'TY:24
(NO TRACE AT ALL LAYERS) (NO TRACE AT ALL LAYERS)
PRESS FIT THUMB SCREW(086.000IZ.0543)
ON SOLDER SIDE
PRESS FIT THUMB SCREW(086.000IZ.0543)
ON SOLDER SIDE
DETAIL  B
SCALE  3.000
(PAD)(NO TRACE AT ALL LAYERS)